(kicad_pcb
	(version 20221018)
	(generator pcbnew)
	(general
    (thickness 1.7403)
  )
	(paper "A4")
	(title_block
    (title "Data Center RDIMM DDR4 Tester")
    (date "2024-09-30")
    (rev "1.2.4")
		(comment 9 "footprint 168 of 690 (U15), pads 1-89 of 676")
	)
	(layers
    (0 "F.Cu" signal)
    (1 "In1.Cu" power)
    (2 "In2.Cu" signal)
    (3 "In3.Cu" power)
    (4 "In4.Cu" power)
    (5 "In5.Cu" signal)
    (6 "In6.Cu" power)
    (7 "In7.Cu" signal)
    (8 "In8.Cu" power)
    (9 "In9.Cu" signal)
    (10 "In10.Cu" power)
    (31 "B.Cu" signal)
    (32 "B.Adhes" user "B.Adhesive")
    (33 "F.Adhes" user "F.Adhesive")
    (34 "B.Paste" user)
    (35 "F.Paste" user)
    (36 "B.SilkS" user "B.Silkscreen")
    (37 "F.SilkS" user "F.Silkscreen")
    (38 "B.Mask" user)
    (39 "F.Mask" user)
    (40 "Dwgs.User" user "User.Drawings")
    (41 "Cmts.User" user "User.Comments")
    (42 "Eco1.User" user "User.Eco1")
    (43 "Eco2.User" user "User.Eco2")
    (44 "Edge.Cuts" user)
    (45 "Margin" user)
    (46 "B.CrtYd" user "B.Courtyard")
    (47 "F.CrtYd" user "F.Courtyard")
    (48 "B.Fab" user)
    (49 "F.Fab" user)
  )
	(footprint "data-center-rdimm-ddr4-tester-footprints:BGA-676_27x27mm_Layout26x26_P1X1mm"
    (layer "F.Cu")
    (at 183.635 90.06 180)
    (descr "FPGA XC7K160TFBG676")
    (tags "FPGA XC7K160TFBG676")
    (property "Author" "Antmicro")
    (property "License" "Apache-2.0")
    (property "MPN" "XC7K160T-FFG676")
    (property "Manufacturer" "AMD-Xilinx")
    (property "Sheetfile" "config-spi.kicad_sch")
    (property "Sheetname" "Config SPI flash")
    (property "ki_description" "Kintex®-7 Field Programmable Gate Array (FPGA) IC 300 4976640 65600 676-BBGA, FCBGA")
    (property "ki_keywords" "SMT, MICROCONTROLLER, IC, FPGA")
    (attr smd)
    (fp_text reference "U15" (at -10.675 -14.7 180) (layer "F.SilkS")
        (effects (font (size 0.7 0.7) (thickness 0.15)) (justify left bottom))
    )
    (fp_text value "XC7K160T-FFG676" (at 0 15.5 180) (layer "F.Fab")
        (effects (font (size 0.7 0.7) (thickness 0.15)) (justify left bottom))
    )
    (pad "A1" smd circle (at -12.5 -12.5 180) (size 0.5 0.5) (layers "F.Cu" "F.Paste" "F.Mask")
      (net 9 "GND") (pinfunction "GND") (pintype "power_in"))
    (pad "A2" smd circle (at -11.5 -12.5 180) (size 0.5 0.5) (layers "F.Cu" "F.Paste" "F.Mask")
      (net 9 "GND") (pinfunction "GND") (pintype "passive"))
    (pad "A3" smd circle (at -10.5 -12.5 180) (size 0.5 0.5) (layers "F.Cu" "F.Paste" "F.Mask")
      (net 418 "GTX_TX0_N") (pinfunction "MGTXTXN3_116") (pintype "bidirectional") (die_length 14.476))
    (pad "A4" smd circle (at -9.5 -12.5 180) (size 0.5 0.5) (layers "F.Cu" "F.Paste" "F.Mask")
      (net 411 "GTX_TX0_P") (pinfunction "MGTXTXP3_116") (pintype "bidirectional") (die_length 14.628))
    (pad "A5" smd circle (at -8.5 -12.5 180) (size 0.5 0.5) (layers "F.Cu" "F.Paste" "F.Mask")
      (net 9 "GND") (pinfunction "GND") (pintype "passive"))
    (pad "A6" smd circle (at -7.5 -12.5 180) (size 0.5 0.5) (layers "F.Cu" "F.Paste" "F.Mask")
      (net 9 "GND") (pinfunction "GND") (pintype "passive"))
    (pad "A7" smd circle (at -6.5 -12.5 180) (size 0.5 0.5) (layers "F.Cu" "F.Paste" "F.Mask")
      (net 9 "GND") (pinfunction "GND") (pintype "passive"))
    (pad "A8" smd circle (at -5.5 -12.5 180) (size 0.5 0.5) (layers "F.Cu" "F.Paste" "F.Mask")
      (net 120 "~{PERST}") (pinfunction "IO_L9N_T1_DQS_16") (pintype "bidirectional") (die_length 19.908))
    (pad "A9" smd circle (at -4.5 -12.5 180) (size 0.5 0.5) (layers "F.Cu" "F.Paste" "F.Mask")
      (net 711 "unconnected-(U15E-IO_L9P_T1_DQS_16-PadA9)") (pinfunction "IO_L9P_T1_DQS_16") (pintype "bidirectional+no_connect") (die_length 19.519))
    (pad "A10" smd circle (at -3.5 -12.5 180) (size 0.5 0.5) (layers "F.Cu" "F.Paste" "F.Mask")
      (net 62 "TMDS_D2_N") (pinfunction "IO_L22N_T3_16") (pintype "bidirectional") (die_length 20.762))
    (pad "A11" smd circle (at -2.5 -12.5 180) (size 0.5 0.5) (layers "F.Cu" "F.Paste" "F.Mask")
      (net 143 "3V3_SYS") (pinfunction "VCCO_16") (pintype "power_in"))
    (pad "A12" smd circle (at -1.5 -12.5 180) (size 0.5 0.5) (layers "F.Cu" "F.Paste" "F.Mask")
      (net 60 "TMDS_D1_N") (pinfunction "IO_L24N_T3_16") (pintype "bidirectional") (die_length 22.422))
    (pad "A13" smd circle (at -0.5 -12.5 180) (size 0.5 0.5) (layers "F.Cu" "F.Paste" "F.Mask")
      (net 59 "TMDS_D1_P") (pinfunction "IO_L24P_T3_16") (pintype "bidirectional") (die_length 22.76))
    (pad "A14" smd circle (at 0.499 -12.5 180) (size 0.5 0.5) (layers "F.Cu" "F.Paste" "F.Mask")
      (net 58 "TMDS_D0_N") (pinfunction "IO_L21N_T3_DQS_16") (pintype "bidirectional") (die_length 18.115))
    (pad "A15" smd circle (at 1.499 -12.5 180) (size 0.5 0.5) (layers "F.Cu" "F.Paste" "F.Mask")
      (net 56 "TMDS_CLK_N") (pinfunction "IO_L23N_T3_16") (pintype "bidirectional") (die_length 18.152))
    (pad "A16" smd circle (at 2.499 -12.5 180) (size 0.5 0.5) (layers "F.Cu" "F.Paste" "F.Mask")
      (net 9 "GND") (pinfunction "GND") (pintype "passive"))
    (pad "A17" smd circle (at 3.499 -12.5 180) (size 0.5 0.5) (layers "F.Cu" "F.Paste" "F.Mask")
      (net 406 "FMC_IO_3_N") (pinfunction "IO_L3N_T0_DQS_AD1N_15") (pintype "bidirectional") (die_length 18.146))
    (pad "A18" smd circle (at 4.499 -12.5 180) (size 0.5 0.5) (layers "F.Cu" "F.Paste" "F.Mask")
      (net 407 "FMC_IO_2_P") (pinfunction "IO_L2P_T0_AD8P_15") (pintype "bidirectional") (die_length 20.209))
    (pad "A19" smd circle (at 5.499 -12.5 180) (size 0.5 0.5) (layers "F.Cu" "F.Paste" "F.Mask")
      (net 416 "FMC_IO_2_N") (pinfunction "IO_L2N_T0_AD8N_15") (pintype "bidirectional") (die_length 19.837))
    (pad "A20" smd circle (at 6.499 -12.5 180) (size 0.5 0.5) (layers "F.Cu" "F.Paste" "F.Mask")
      (net 784 "HOT_SWAP_YELLOW") (pinfunction "IO_L8N_T1_D12_14") (pintype "bidirectional") (die_length 22.195))
    (pad "A21" smd circle (at 7.499 -12.5 180) (size 0.5 0.5) (layers "F.Cu" "F.Paste" "F.Mask")
      (net 143 "3V3_SYS") (pinfunction "VCCO_14") (pintype "power_in"))
    (pad "A22" smd circle (at 8.499 -12.5 180) (size 0.5 0.5) (layers "F.Cu" "F.Paste" "F.Mask")
      (net 22 "QSPI_DQ3") (pinfunction "IO_L2N_T0_D03_14") (pintype "bidirectional") (die_length 21.482))
    (pad "A23" smd circle (at 9.499 -12.5 180) (size 0.5 0.5) (layers "F.Cu" "F.Paste" "F.Mask")
      (net 141 "UART1_TX") (pinfunction "IO_L4P_T0_D04_14") (pintype "bidirectional") (die_length 21.833))
    (pad "A24" smd circle (at 10.499 -12.5 180) (size 0.5 0.5) (layers "F.Cu" "F.Paste" "F.Mask")
      (net 139 "UART1_RX") (pinfunction "IO_L4N_T0_D05_14") (pintype "bidirectional") (die_length 22.897))
    (pad "A25" smd circle (at 11.499 -12.5 180) (size 0.5 0.5) (layers "F.Cu" "F.Paste" "F.Mask")
      (net 20 "QSPI_DQ1") (pinfunction "IO_L1N_T0_D01_DIN_14") (pintype "bidirectional") (die_length 23.845))
    (pad "A26" smd circle (at 12.499 -12.5 180) (size 0.5 0.5) (layers "F.Cu" "F.Paste" "F.Mask")
      (net 9 "GND") (pinfunction "GND") (pintype "passive"))
    (pad "AA1" smd circle (at -12.5 7.499 180) (size 0.5 0.5) (layers "F.Cu" "F.Paste" "F.Mask")
      (net 77 "VDDQ") (pinfunction "VCCO_34") (pintype "power_in"))
    (pad "AA2" smd circle (at -11.5 7.499 180) (size 0.5 0.5) (layers "F.Cu" "F.Paste" "F.Mask")
      (net 320 "DQS1_N") (pinfunction "IO_L12N_T1_MRCC_34") (pintype "bidirectional") (die_length 19.51))
    (pad "AA3" smd circle (at -10.5 7.499 180) (size 0.5 0.5) (layers "F.Cu" "F.Paste" "F.Mask")
      (net 318 "DQS1_P") (pinfunction "IO_L12P_T1_MRCC_34") (pintype "bidirectional") (die_length 19.161))
    (pad "AA4" smd circle (at -9.5 7.499 180) (size 0.5 0.5) (layers "F.Cu" "F.Paste" "F.Mask")
      (net 247 "DQ14") (pinfunction "IO_L13P_T2_MRCC_34") (pintype "bidirectional") (die_length 19.112))
    (pad "AA5" smd circle (at -8.5 7.499 180) (size 0.5 0.5) (layers "F.Cu" "F.Paste" "F.Mask")
      (net 244 "DQ6") (pinfunction "IO_L15P_T2_DQS_34") (pintype "bidirectional") (die_length 18.268))
    (pad "AA6" smd circle (at -7.5 7.499 180) (size 0.5 0.5) (layers "F.Cu" "F.Paste" "F.Mask")
      (net 9 "GND") (pinfunction "GND") (pintype "passive"))
    (pad "AA7" smd circle (at -6.5 7.499 180) (size 0.5 0.5) (layers "F.Cu" "F.Paste" "F.Mask")
      (net 290 "CKE1\\NC") (pinfunction "IO_L8N_T1_33") (pintype "bidirectional") (die_length 16.325))
    (pad "AA8" smd circle (at -5.5 7.499 180) (size 0.5 0.5) (layers "F.Cu" "F.Paste" "F.Mask")
      (net 261 "CKE0") (pinfunction "IO_L8P_T1_33") (pintype "bidirectional") (die_length 15.251))
    (pad "AA9" smd circle (at -4.5 7.499 180) (size 0.5 0.5) (layers "F.Cu" "F.Paste" "F.Mask")
      (net 263 "BG0") (pinfunction "IO_L11P_T1_SRCC_33") (pintype "bidirectional") (die_length 13.773))
    (pad "AA10" smd circle (at -3.5 7.499 180) (size 0.5 0.5) (layers "F.Cu" "F.Paste" "F.Mask")
      (net 712 "unconnected-(U15G-IO_L14P_T2_SRCC_33-PadAA10)") (pinfunction "IO_L14P_T2_SRCC_33") (pintype "bidirectional+no_connect") (die_length 14.881))
    (pad "AA11" smd circle (at -2.5 7.499 180) (size 0.5 0.5) (layers "F.Cu" "F.Paste" "F.Mask")
      (net 77 "VDDQ") (pinfunction "VCCO_33") (pintype "power_in"))
    (pad "AA12" smd circle (at -1.5 7.499 180) (size 0.5 0.5) (layers "F.Cu" "F.Paste" "F.Mask")
      (net 238 "~{RAS}\\A16") (pinfunction "IO_L16N_T2_33") (pintype "bidirectional") (die_length 14.923))
    (pad "AA13" smd circle (at -0.5 7.499 180) (size 0.5 0.5) (layers "F.Cu" "F.Paste" "F.Mask")
      (net 210 "~{WE}\\A14") (pinfunction "IO_L16P_T2_33") (pintype "bidirectional") (die_length 16.493))
    (pad "AA14" smd circle (at 0.499 7.499 180) (size 0.5 0.5) (layers "F.Cu" "F.Paste" "F.Mask")
      (net 223 "DQ52") (pinfunction "IO_L7P_T1_32") (pintype "bidirectional") (die_length 11.726))
    (pad "AA15" smd circle (at 1.499 7.499 180) (size 0.5 0.5) (layers "F.Cu" "F.Paste" "F.Mask")
      (net 225 "DQ48") (pinfunction "IO_L7N_T1_32") (pintype "bidirectional") (die_length 11.467))
    (pad "AA16" smd circle (at 2.499 7.499 180) (size 0.5 0.5) (layers "F.Cu" "F.Paste" "F.Mask")
      (net 9 "GND") (pinfunction "GND") (pintype "passive"))
    (pad "AA17" smd circle (at 3.499 7.499 180) (size 0.5 0.5) (layers "F.Cu" "F.Paste" "F.Mask")
      (net 339 "DQS15_P") (pinfunction "IO_L11P_T1_SRCC_32") (pintype "bidirectional") (die_length 14.572))
    (pad "AA18" smd circle (at 4.499 7.499 180) (size 0.5 0.5) (layers "F.Cu" "F.Paste" "F.Mask")
      (net 341 "DQS15_N") (pinfunction "IO_L11N_T1_SRCC_32") (pintype "bidirectional") (die_length 14.747))
    (pad "AA19" smd circle (at 5.499 7.499 180) (size 0.5 0.5) (layers "F.Cu" "F.Paste" "F.Mask")
      (net 219 "DQ50") (pinfunction "IO_L16P_T2_32") (pintype "bidirectional") (die_length 19.389))
    (pad "AA20" smd circle (at 6.499 7.499 180) (size 0.5 0.5) (layers "F.Cu" "F.Paste" "F.Mask")
      (net 193 "DQ51") (pinfunction "IO_L16N_T2_32") (pintype "bidirectional") (die_length 21.053))
    (pad "AA21" smd circle (at 7.499 7.499 180) (size 0.5 0.5) (layers "F.Cu" "F.Paste" "F.Mask")
      (net 143 "3V3_SYS") (pinfunction "VCCO_12") (pintype "power_in"))
    (pad "AA22" smd circle (at 8.499 7.499 180) (size 0.5 0.5) (layers "F.Cu" "F.Paste" "F.Mask")
      (net 28 "ETH_RSTN") (pinfunction "IO_L13N_T2_MRCC_12") (pintype "bidirectional") (die_length 11.687))
    (pad "AA23" smd circle (at 9.499 7.499 180) (size 0.5 0.5) (layers "F.Cu" "F.Paste" "F.Mask")
      (net 30 "ETH_REF_CLK") (pinfunction "IO_L11P_T1_SRCC_12") (pintype "bidirectional") (die_length 13.863))
    (pad "AA24" smd circle (at 10.499 7.499 180) (size 0.5 0.5) (layers "F.Cu" "F.Paste" "F.Mask")
      (net 34 "ETH_TX_CLK") (pinfunction "IO_L12N_T1_MRCC_12") (pintype "bidirectional") (die_length 13.119))
    (pad "AA25" smd circle (at 11.499 7.499 180) (size 0.5 0.5) (layers "F.Cu" "F.Paste" "F.Mask")
      (net 39 "ETH_MDC") (pinfunction "IO_L7P_T1_12") (pintype "bidirectional") (die_length 15.139))
    (pad "AA26" smd circle (at 12.499 7.499 180) (size 0.5 0.5) (layers "F.Cu" "F.Paste" "F.Mask")
      (net 9 "GND") (pinfunction "GND") (pintype "passive"))
    (pad "AB1" smd circle (at -12.5 8.499 180) (size 0.5 0.5) (layers "F.Cu" "F.Paste" "F.Mask")
      (net 322 "DQS2_P") (pinfunction "IO_L9P_T1_DQS_34") (pintype "bidirectional") (die_length 21.468))
    (pad "AB2" smd circle (at -11.5 8.499 180) (size 0.5 0.5) (layers "F.Cu" "F.Paste" "F.Mask")
      (net 251 "DQ22") (pinfunction "IO_L11P_T1_SRCC_34") (pintype "bidirectional") (die_length 21.477))
    (pad "AB3" smd circle (at -10.5 8.499 180) (size 0.5 0.5) (layers "F.Cu" "F.Paste" "F.Mask")
      (net 9 "GND") (pinfunction "GND") (pintype "passive"))
    (pad "AB4" smd circle (at -9.5 8.499 180) (size 0.5 0.5) (layers "F.Cu" "F.Paste" "F.Mask")
      (net 273 "DQ15") (pinfunction "IO_L13N_T2_MRCC_34") (pintype "bidirectional") (die_length 19.11))
    (pad "AB5" smd circle (at -8.5 8.499 180) (size 0.5 0.5) (layers "F.Cu" "F.Paste" "F.Mask")
      (net 297 "DQ7") (pinfunction "IO_L15N_T2_DQS_34") (pintype "bidirectional") (die_length 17.889))
    (pad "AB6" smd circle (at -7.5 8.499 180) (size 0.5 0.5) (layers "F.Cu" "F.Paste" "F.Mask")
      (net 243 "DQ2") (pinfunction "IO_L16P_T2_34") (pintype "bidirectional") (die_length 18.462))
    (pad "AB7" smd circle (at -6.5 8.499 180) (size 0.5 0.5) (layers "F.Cu" "F.Paste" "F.Mask")
      (net 283 "A11") (pinfunction "IO_L10P_T1_33") (pintype "bidirectional") (die_length 14.818))
    (pad "AB8" smd circle (at -5.5 8.499 180) (size 0.5 0.5) (layers "F.Cu" "F.Paste" "F.Mask")
      (net 77 "VDDQ") (pinfunction "VCCO_33") (pintype "passive"))
    (pad "AB9" smd circle (at -4.5 8.499 180) (size 0.5 0.5) (layers "F.Cu" "F.Paste" "F.Mask")
      (net 267 "A6") (pinfunction "IO_L11N_T1_SRCC_33") (pintype "bidirectional") (die_length 13.992))
    (pad "AB10" smd circle (at -3.5 8.499 180) (size 0.5 0.5) (layers "F.Cu" "F.Paste" "F.Mask")
      (net 211 "BA1") (pinfunction "IO_L14N_T2_SRCC_33") (pintype "bidirectional") (die_length 15.337))
    (pad "AB11" smd circle (at -2.5 8.499 180) (size 0.5 0.5) (layers "F.Cu" "F.Paste" "F.Mask")
      (net 239 "BA0") (pinfunction "IO_L13P_T2_MRCC_33") (pintype "bidirectional") (die_length 18.178))
    (pad "AB12" smd circle (at -1.5 8.499 180) (size 0.5 0.5) (layers "F.Cu" "F.Paste" "F.Mask")
      (net 353 "CK1_P") (pinfunction "IO_L15P_T2_DQS_33") (pintype "bidirectional") (die_length 19.224))
    (pad "AB13" smd circle (at -0.5 8.499 180) (size 0.5 0.5) (layers "F.Cu" "F.Paste" "F.Mask")
      (net 9 "GND") (pinfunction "GND") (pintype "passive"))
    (pad "AB14" smd circle (at 0.499 8.499 180) (size 0.5 0.5) (layers "F.Cu" "F.Paste" "F.Mask")
      (net 229 "DQ40") (pinfunction "IO_L10P_T1_32") (pintype "bidirectional") (die_length 14.652))
    (pad "AB15" smd circle (at 1.499 8.499 180) (size 0.5 0.5) (layers "F.Cu" "F.Paste" "F.Mask")
      (net 188 "DQ43") (pinfunction "IO_L10N_T1_32") (pintype "bidirectional") (die_length 16.86))
    (pad "AB16" smd circle (at 2.499 8.499 180) (size 0.5 0.5) (layers "F.Cu" "F.Paste" "F.Mask")
      (net 204 "DQ53") (pinfunction "IO_L12P_T1_MRCC_32") (pintype "bidirectional") (die_length 17.498))
    (pad "AB17" smd circle (at 3.499 8.499 180) (size 0.5 0.5) (layers "F.Cu" "F.Paste" "F.Mask")
      (net 190 "DQ49") (pinfunction "IO_L14P_T2_SRCC_32") (pintype "bidirectional") (die_length 16.709))
    (pad "AB18" smd circle (at 4.499 8.499 180) (size 0.5 0.5) (layers "F.Cu" "F.Paste" "F.Mask")
      (net 77 "VDDQ") (pinfunction "VCCO_32") (pintype "power_in"))
    (pad "AB19" smd circle (at 5.499 8.499 180) (size 0.5 0.5) (layers "F.Cu" "F.Paste" "F.Mask")
      (net 220 "DQ54") (pinfunction "IO_L18P_T2_32") (pintype "bidirectional") (die_length 21.632))
    (pad "AB20" smd circle (at 6.499 8.499 180) (size 0.5 0.5) (layers "F.Cu" "F.Paste" "F.Mask")
      (net 206 "DQ55") (pinfunction "IO_L18N_T2_32") (pintype "bidirectional") (die_length 20.965))
    (pad "AB21" smd circle (at 7.499 8.499 180) (size 0.5 0.5) (layers "F.Cu" "F.Paste" "F.Mask")
      (net 713 "unconnected-(U15A-IO_L18P_T2_12-PadAB21)") (pinfunction "IO_L18P_T2_12") (pintype "bidirectional+no_connect") (die_length 11.49))
    (pad "AB22" smd circle (at 8.499 8.499 180) (size 0.5 0.5) (layers "F.Cu" "F.Paste" "F.Mask")
      (net 714 "unconnected-(U15A-IO_L17P_T2_12-PadAB22)") (pinfunction "IO_L17P_T2_12") (pintype "bidirectional+no_connect") (die_length 12.162))
    (pad "AB23" smd circle (at 9.499 8.499 180) (size 0.5 0.5) (layers "F.Cu" "F.Paste" "F.Mask")
      (net 9 "GND") (pinfunction "GND") (pintype "passive"))
    (pad "AB24" smd circle (at 10.499 8.499 180) (size 0.5 0.5) (layers "F.Cu" "F.Paste" "F.Mask")
      (net 715 "unconnected-(U15A-IO_L11N_T1_SRCC_12-PadAB24)") (pinfunction "IO_L11N_T1_SRCC_12") (pintype "bidirectional+no_connect") (die_length 14.571))
    (pad "AB25" smd circle (at 11.499 8.499 180) (size 0.5 0.5) (layers "F.Cu" "F.Paste" "F.Mask")
      (net 716 "unconnected-(U15A-IO_L7N_T1_12-PadAB25)") (pinfunction "IO_L7N_T1_12") (pintype "bidirectional+no_connect") (die_length 16.017))
    (pad "AB26" smd circle (at 12.499 8.499 180) (size 0.5 0.5) (layers "F.Cu" "F.Paste" "F.Mask")
      (net 29 "ETH_MDIO") (pinfunction "IO_L9P_T1_DQS_12") (pintype "bidirectional") (die_length 16.487))
    (pad "AC1" smd circle (at -12.5 9.499 180) (size 0.5 0.5) (layers "F.Cu" "F.Paste" "F.Mask")
      (net 324 "DQS2_N") (pinfunction "IO_L9N_T1_DQS_34") (pintype "bidirectional") (die_length 21.84))
    (pad "AC2" smd circle (at -11.5 9.499 180) (size 0.5 0.5) (layers "F.Cu" "F.Paste" "F.Mask")
      (net 253 "DQ18") (pinfunction "IO_L11N_T1_SRCC_34") (pintype "bidirectional") (die_length 21.727))
    (pad "AC3" smd circle (at -10.5 9.499 180) (size 0.5 0.5) (layers "F.Cu" "F.Paste" "F.Mask")
      (net 248 "DQ10") (pinfunction "IO_L14N_T2_SRCC_34") (pintype "bidirectional") (die_length 20.603))
    (pad "AC4" smd circle (at -9.5 9.499 180) (size 0.5 0.5) (layers "F.Cu" "F.Paste" "F.Mask")
      (net 274 "DQ11") (pinfunction "IO_L14P_T2_SRCC_34") (pintype "bidirectional") (die_length 20.232))
    (pad "AC5" smd circle (at -8.5 9.499 180) (size 0.5 0.5) (layers "F.Cu" "F.Paste" "F.Mask")
      (net 77 "VDDQ") (pinfunction "VCCO_34") (pintype "passive"))
    (pad "AC6" smd circle (at -7.5 9.499 180) (size 0.5 0.5) (layers "F.Cu" "F.Paste" "F.Mask")
      (net 292 "DQ3") (pinfunction "IO_L16N_T2_34") (pintype "bidirectional") (die_length 19.298))
    (pad "AC7" smd circle (at -6.5 9.499 180) (size 0.5 0.5) (layers "F.Cu" "F.Paste" "F.Mask")
      (net 265 "A12\\~{BC}") (pinfunction "IO_L10N_T1_33") (pintype "bidirectional") (die_length 16.292))
    (pad "AC8" smd circle (at -5.5 9.499 180) (size 0.5 0.5) (layers "F.Cu" "F.Paste" "F.Mask")
      (net 717 "unconnected-(U15G-IO_L9P_T1_DQS_33-PadAC8)") (pinfunction "IO_L9P_T1_DQS_33") (pintype "bidirectional+no_connect") (die_length 16.788))
    (pad "AC9" smd circle (at -4.5 9.499 180) (size 0.5 0.5) (layers "F.Cu" "F.Paste" "F.Mask")
      (net 289 "A4") (pinfunction "IO_L12P_T1_MRCC_33") (pintype "bidirectional") (die_length 16.857))
    (pad "AC10" smd circle (at -3.5 9.499 180) (size 0.5 0.5) (layers "F.Cu" "F.Paste" "F.Mask")
      (net 9 "GND") (pinfunction "GND") (pintype "passive"))
    (pad "AC11" smd circle (at -2.5 9.499 180) (size 0.5 0.5) (layers "F.Cu" "F.Paste" "F.Mask")
      (net 270 "A1") (pinfunction "IO_L13N_T2_MRCC_33") (pintype "bidirectional") (die_length 17.813))
  )
)
